# BASEBOARD_FAB2 (Tioga Pass) — schematic netlist excerpt (pin names and nets, part order shuffled) for the footprints in the layout excerpt that follows; sources: Cadence DE-HDL packaged netlist, KiCad conversion of Wiwynn_Tioga_Pass_MB.brd

EU1B1  PXM1310B  IC  pkg QFN  page 226
  BPWM1  = NC
  DNC(0)  = NC
  APWM3  = NC
  APWM2  = VR_PVDDQ_KLM_PWM2
  APWM1  = VR_PVDDQ_KLM_PWM1
  SDA  = SMB_VR_STBY_LVC3_SDA
  SCL  = SMB_VR_STBY_LVC3_SCL
  RESET_N  = NC
  AVRRDY  = PWRGD_PVDDQ_KLM_R
  AVREN  = VR_PVDDQ_KLM_VREN
  VRHOT_N  = IRQ_PVDDQ_KLM_VRHOT_LVT3_R_N
  PINALRT_N  = NC
  MP0  = PU_VR_PVDDQ_KLM_FAULT1
  MP1  = NC_PVDDQ_KLM_GP1
  VCLK  = SVID_CLK_PVDDQ_KLM
  VDIO  = SVID_VDIO_PVDDQ_KLM
  VALRT_N  = SVID_ALERT_PVDDQ_KLM
  MP2  = NC_PVDDQ_KLM_GP0
  AVSEN  = VR_PVDDQ_KLM_AVSP
  AVREF  = VSENSE_PVDDQ_KLM_N
  AIREF1  = VR_PVDDQ_KLM_AIREF1
  AISEN1  = ISENSE_PVDDQ_KLM_PH1_IMON
  AIREF2  = VR_PVDDQ_KLM_AIREF2
  AISEN2  = ISENSE_PVDDQ_KLM_PH2_IMON
  AIREF3  = NC
  AISEN3  = NC
  GND  = GND
  DNC(1)  = NC
  BVSEN  = NC
  BVREF  = NC
  BIREF1  = NC
  BISEN1  = GND
  XADDR2  = VR_PVDDQ_KLM_XADDR2
  BTSEN  = NC
  ATSEN  = A_TSENSE_PVDDQ_KLM
  XADDR1  = VR_PVDDQ_KLM_XADDR1
  VINSEN  = VR_PVDDQ_KLM_VINSEN
  IINSEN  = VR_PVDDQ_KLM_AIINSEN
  VDD  = VR_PVDDQ_KLM_VDD
  VD12  = VR_PVDDQ_KLM_VD12
  THPAD  = GND

(kicad_pcb
	(version 20260206)
	(generator "pcbnew")
	(generator_version "10.0")
	(general
		(thickness 1.6)
		(legacy_teardrops no)
	)
	(paper "A4")
	(title_block
		(title "Wiwynn_Tioga_Pass_MB.brd")
		(comment 1 "Tioga Pass / footprint 1727 of 4770 (EU1B1), pads 1-17 of 41")
	)
	(layers
		(0 "F.Cu" signal "TOP")
		(4 "In1.Cu" signal "L2GND")
		(6 "In2.Cu" signal "L3")
		(8 "In3.Cu" signal "L4GND")
		(10 "In4.Cu" signal "L5")
		(12 "In5.Cu" signal "L6GND")
		(14 "In6.Cu" signal "L7VCC")
		(16 "In7.Cu" signal "L8VCC")
		(18 "In8.Cu" signal "L9GND")
		(20 "In9.Cu" signal "L10")
		(22 "In10.Cu" signal "L11GND")
		(24 "In11.Cu" signal "L12")
		(26 "In12.Cu" signal "L13GND")
		(2 "B.Cu" signal "BOTTOM")
		(9 "F.Adhes" user "F.Adhesive")
		(11 "B.Adhes" user "B.Adhesive")
		(13 "F.Paste" user "Package Geometry/Pastemask Top")
		(15 "B.Paste" user "Package Geometry/Pastemask Bottom")
		(5 "F.SilkS" user "Ref Des/Silkscreen Top")
		(7 "B.SilkS" user "Ref Des/Silkscreen Bottom")
		(1 "F.Mask" user "Board Geometry/Soldermask Top")
		(3 "B.Mask" user "Board Geometry/Soldermask Bottom")
		(17 "Dwgs.User" user "User.Drawings")
		(19 "Cmts.User" user "User.Comments")
		(21 "Eco1.User" user "User.Eco1")
		(23 "Eco2.User" user "User.Eco2")
		(25 "Edge.Cuts" user "Board Geometry/Outline")
		(27 "Margin" user)
		(31 "F.CrtYd" user "Package Geometry/Place Bound Top")
		(29 "B.CrtYd" user "Package Geometry/Place Bound Bottom")
		(35 "F.Fab" user "Ref Des/Assembly Top")
		(33 "B.Fab" user "Ref Des/Assembly Bottom")
	)
	(footprint ""
		(layer "F.Cu")
		(at 2.0574 -127.9652 -90)
		(property "Reference" "EU1B1"
			(at 3.76047 4.0132 0)
			(unlocked yes)
			(layer "F.SilkS")
			(effects
				(font
					(size 0.7874 0.5842)
					(thickness 0.1524)
				)
				(justify left)
			)
		)
		(property "Value" ""
			(at 0 0 270)
			(layer "F.Fab")
			(effects
				(font
					(size 1.27 1.27)
				)
			)
		)
		(duplicate_pad_numbers_are_jumpers no)
		(pad "1" smd custom
			(at -2.4511 -1.800098 270)
			(size 0.0508 0.0508)
			(layers "F.Cu" "F.Mask" "F.Paste")
			(net "Net_287")
			(options
				(clearance outline)
				(anchor circle)
			)
			(primitives
				(gr_poly
					(pts
						(arc
							(start 0.254 -0.1016)
							(mid 0.3556 0)
							(end 0.254 0.1016)
						)
						(xy -0.3556 0.1016) (xy -0.3556 -0.1016)
					)
					(width 0)
					(fill yes)
				)
			)
		)
		(pad "2" smd custom
			(at -2.4511 -1.400048 270)
			(size 0.0508 0.0508)
			(layers "F.Cu" "F.Mask" "F.Paste")
			(net "Net_271")
			(options
				(clearance outline)
				(anchor circle)
			)
			(primitives
				(gr_poly
					(pts
						(arc
							(start 0.254 -0.1016)
							(mid 0.3556 0)
							(end 0.254 0.1016)
						)
						(xy -0.3556 0.1016) (xy -0.3556 -0.1016)
					)
					(width 0)
					(fill yes)
				)
			)
		)
		(pad "3" smd custom
			(at -2.4511 -0.999998 270)
			(size 0.0508 0.0508)
			(layers "F.Cu" "F.Mask" "F.Paste")
			(net "Net_250")
			(options
				(clearance outline)
				(anchor circle)
			)
			(primitives
				(gr_poly
					(pts
						(arc
							(start 0.254 -0.1016)
							(mid 0.3556 0)
							(end 0.254 0.1016)
						)
						(xy -0.3556 0.1016) (xy -0.3556 -0.1016)
					)
					(width 0)
					(fill yes)
				)
			)
		)
		(pad "4" smd custom
			(at -2.4511 -0.599948 270)
			(size 0.0508 0.0508)
			(layers "F.Cu" "F.Mask" "F.Paste")
			(net "VR_PVDDQ_KLM_PWM2")
			(options
				(clearance outline)
				(anchor circle)
			)
			(primitives
				(gr_poly
					(pts
						(arc
							(start 0.254 -0.1016)
							(mid 0.3556 0)
							(end 0.254 0.1016)
						)
						(xy -0.3556 0.1016) (xy -0.3556 -0.1016)
					)
					(width 0)
					(fill yes)
				)
			)
		)
		(pad "5" smd custom
			(at -2.4511 -0.199898 270)
			(size 0.0508 0.0508)
			(layers "F.Cu" "F.Mask" "F.Paste")
			(net "VR_PVDDQ_KLM_PWM1")
			(options
				(clearance outline)
				(anchor circle)
			)
			(primitives
				(gr_poly
					(pts
						(arc
							(start 0.254 -0.1016)
							(mid 0.3556 0)
							(end 0.254 0.1016)
						)
						(xy -0.3556 0.1016) (xy -0.3556 -0.1016)
					)
					(width 0)
					(fill yes)
				)
			)
		)
		(pad "6" smd custom
			(at -2.4511 0.199898 270)
			(size 0.0508 0.0508)
			(layers "F.Cu" "F.Mask" "F.Paste")
			(net "SMB_VR_STBY_LVC3_SDA")
			(options
				(clearance outline)
				(anchor circle)
			)
			(primitives
				(gr_poly
					(pts
						(arc
							(start 0.254 -0.1016)
							(mid 0.3556 0)
							(end 0.254 0.1016)
						)
						(xy -0.3556 0.1016) (xy -0.3556 -0.1016)
					)
					(width 0)
					(fill yes)
				)
			)
		)
		(pad "7" smd custom
			(at -2.4511 0.599948 270)
			(size 0.0508 0.0508)
			(layers "F.Cu" "F.Mask" "F.Paste")
			(net "SMB_VR_STBY_LVC3_SCL")
			(options
				(clearance outline)
				(anchor circle)
			)
			(primitives
				(gr_poly
					(pts
						(arc
							(start 0.254 -0.1016)
							(mid 0.3556 0)
							(end 0.254 0.1016)
						)
						(xy -0.3556 0.1016) (xy -0.3556 -0.1016)
					)
					(width 0)
					(fill yes)
				)
			)
		)
		(pad "8" smd custom
			(at -2.4511 0.999998 270)
			(size 0.0508 0.0508)
			(layers "F.Cu" "F.Mask" "F.Paste")
			(net "Net_288")
			(options
				(clearance outline)
				(anchor circle)
			)
			(primitives
				(gr_poly
					(pts
						(arc
							(start 0.254 -0.1016)
							(mid 0.3556 0)
							(end 0.254 0.1016)
						)
						(xy -0.3556 0.1016) (xy -0.3556 -0.1016)
					)
					(width 0)
					(fill yes)
				)
			)
		)
		(pad "9" smd custom
			(at -2.4511 1.400048 270)
			(size 0.0508 0.0508)
			(layers "F.Cu" "F.Mask" "F.Paste")
			(net "PWRGD_PVDDQ_KLM_R")
			(options
				(clearance outline)
				(anchor circle)
			)
			(primitives
				(gr_poly
					(pts
						(arc
							(start 0.254 -0.1016)
							(mid 0.3556 0)
							(end 0.254 0.1016)
						)
						(xy -0.3556 0.1016) (xy -0.3556 -0.1016)
					)
					(width 0)
					(fill yes)
				)
			)
		)
		(pad "10" smd custom
			(at -2.4511 1.800098 270)
			(size 0.0508 0.0508)
			(layers "F.Cu" "F.Mask" "F.Paste")
			(net "VR_PVDDQ_KLM_VREN")
			(options
				(clearance outline)
				(anchor circle)
			)
			(primitives
				(gr_poly
					(pts
						(arc
							(start 0.254 -0.1016)
							(mid 0.3556 0)
							(end 0.254 0.1016)
						)
						(xy -0.3556 0.1016) (xy -0.3556 -0.1016)
					)
					(width 0)
					(fill yes)
				)
			)
		)
		(pad "11" smd custom
			(at -1.800098 2.4511 270)
			(size 0.0508 0.0508)
			(layers "F.Cu" "F.Mask" "F.Paste")
			(net "IRQ_PVDDQ_KLM_VRHOT_LVT3_R_N")
			(options
				(clearance outline)
				(anchor circle)
			)
			(primitives
				(gr_poly
					(pts
						(arc
							(start -0.1016 -0.254)
							(mid 0 -0.3556)
							(end 0.1016 -0.254)
						)
						(xy 0.1016 0.3556) (xy -0.1016 0.3556)
					)
					(width 0)
					(fill yes)
				)
			)
		)
		(pad "12" smd custom
			(at -1.400048 2.4511 270)
			(size 0.0508 0.0508)
			(layers "F.Cu" "F.Mask" "F.Paste")
			(net "Net_239")
			(options
				(clearance outline)
				(anchor circle)
			)
			(primitives
				(gr_poly
					(pts
						(arc
							(start -0.1016 -0.254)
							(mid 0 -0.3556)
							(end 0.1016 -0.254)
						)
						(xy 0.1016 0.3556) (xy -0.1016 0.3556)
					)
					(width 0)
					(fill yes)
				)
			)
		)
		(pad "13" smd custom
			(at -0.999998 2.4511 270)
			(size 0.0508 0.0508)
			(layers "F.Cu" "F.Mask" "F.Paste")
			(net "PU_VR_PVDDQ_KLM_FAULT1")
			(options
				(clearance outline)
				(anchor circle)
			)
			(primitives
				(gr_poly
					(pts
						(arc
							(start -0.1016 -0.254)
							(mid 0 -0.3556)
							(end 0.1016 -0.254)
						)
						(xy 0.1016 0.3556) (xy -0.1016 0.3556)
					)
					(width 0)
					(fill yes)
				)
			)
		)
		(pad "14" smd custom
			(at -0.599948 2.4511 270)
			(size 0.0508 0.0508)
			(layers "F.Cu" "F.Mask" "F.Paste")
			(net "NC_PVDDQ_KLM_GP1")
			(options
				(clearance outline)
				(anchor circle)
			)
			(primitives
				(gr_poly
					(pts
						(arc
							(start -0.1016 -0.254)
							(mid 0 -0.3556)
							(end 0.1016 -0.254)
						)
						(xy 0.1016 0.3556) (xy -0.1016 0.3556)
					)
					(width 0)
					(fill yes)
				)
			)
		)
		(pad "15" smd custom
			(at -0.199898 2.4511 270)
			(size 0.0508 0.0508)
			(layers "F.Cu" "F.Mask" "F.Paste")
			(net "SVID_CLK_PVDDQ_KLM")
			(options
				(clearance outline)
				(anchor circle)
			)
			(primitives
				(gr_poly
					(pts
						(arc
							(start -0.1016 -0.254)
							(mid 0 -0.3556)
							(end 0.1016 -0.254)
						)
						(xy 0.1016 0.3556) (xy -0.1016 0.3556)
					)
					(width 0)
					(fill yes)
				)
			)
		)
		(pad "16" smd custom
			(at 0.199898 2.4511 270)
			(size 0.0508 0.0508)
			(layers "F.Cu" "F.Mask" "F.Paste")
			(net "SVID_VDIO_PVDDQ_KLM")
			(options
				(clearance outline)
				(anchor circle)
			)
			(primitives
				(gr_poly
					(pts
						(arc
							(start -0.1016 -0.254)
							(mid 0 -0.3556)
							(end 0.1016 -0.254)
						)
						(xy 0.1016 0.3556) (xy -0.1016 0.3556)
					)
					(width 0)
					(fill yes)
				)
			)
		)
		(pad "17" smd custom
			(at 0.599948 2.4511 270)
			(size 0.0508 0.0508)
			(layers "F.Cu" "F.Mask" "F.Paste")
			(net "SVID_ALERT_PVDDQ_KLM")
			(options
				(clearance outline)
				(anchor circle)
			)
			(primitives
				(gr_poly
					(pts
						(arc
							(start -0.1016 -0.254)
							(mid 0 -0.3556)
							(end 0.1016 -0.254)
						)
						(xy 0.1016 0.3556) (xy -0.1016 0.3556)
					)
					(width 0)
					(fill yes)
				)
			)
		)
	)
)
